(kicad_pcb
	(version 20260206)
	(generator "pcbnew")
	(generator_version "10.0")
	(general
		(thickness 1.6)
		(legacy_teardrops no)
	)
	(paper "A4")
	(title_block
		(title "9052_F0T_PDB_Converter_Brick_F_V03_1208_1600_OCP.brd")
		(comment 1 "Grand Teton / footprints 302-307 of 578")
	)
	(layers
		(0 "F.Cu" signal "TOP")
		(4 "In1.Cu" signal "GND")
		(6 "In2.Cu" signal "IN1")
		(8 "In3.Cu" signal "GND1")
		(10 "In4.Cu" signal "VCC")
		(12 "In5.Cu" signal "VCC1")
		(14 "In6.Cu" signal "GND2")
		(16 "In7.Cu" signal "IN2")
		(18 "In8.Cu" signal "GND3")
		(2 "B.Cu" signal "BOTTOM")
		(9 "F.Adhes" user "F.Adhesive")
		(11 "B.Adhes" user "B.Adhesive")
		(13 "F.Paste" user "Package Geometry/Pastemask Top")
		(15 "B.Paste" user "Package Geometry/Pastemask Bottom")
		(5 "F.SilkS" user "Ref Des/Silkscreen Top")
		(7 "B.SilkS" user "Ref Des/Silkscreen Bottom")
		(1 "F.Mask" user "Board Geometry/Soldermask Top")
		(3 "B.Mask" user "Board Geometry/Soldermask Bottom")
		(17 "Dwgs.User" user "User.Drawings")
		(19 "Cmts.User" user "User.Comments")
		(21 "Eco1.User" user "User.Eco1")
		(23 "Eco2.User" user "User.Eco2")
		(25 "Edge.Cuts" user "Board Geometry/Outline")
		(27 "Margin" user)
		(31 "F.CrtYd" user "Package Geometry/Place Bound Top")
		(29 "B.CrtYd" user "Package Geometry/Place Bound Bottom")
		(35 "F.Fab" user "Ref Des/Assembly Top")
		(33 "B.Fab" user "Ref Des/Assembly Bottom")
	)
	(footprint ""
		(layer "B.Cu")
		(at 272.288 -28.956)
		(property "Reference" "C102"
			(at 0 0 0)
			(layer "B.SilkS")
			(hide yes)
			(effects
				(font
					(size 1.27 1.27)
				)
				(justify mirror)
			)
		)
		(property "Value" ""
			(at 0 0 0)
			(layer "B.Fab")
			(effects
				(font
					(size 1.27 1.27)
				)
				(justify mirror)
			)
		)
		(duplicate_pad_numbers_are_jumpers no)
		(fp_line
			(start -0.7874 -0.4064)
			(end -0.7874 0.4064)
			(stroke
				(width 0.1524)
				(type default)
			)
			(layer "B.SilkS")
		)
		(fp_line
			(start -0.7874 0.4064)
			(end 0.7874 0.4064)
			(stroke
				(width 0.1524)
				(type default)
			)
			(layer "B.SilkS")
		)
		(fp_line
			(start 0.7874 -0.4064)
			(end -0.7874 -0.4064)
			(stroke
				(width 0.1524)
				(type default)
			)
			(layer "B.SilkS")
		)
		(fp_line
			(start 0.7874 0.4064)
			(end 0.7874 -0.4064)
			(stroke
				(width 0.1524)
				(type default)
			)
			(layer "B.SilkS")
		)
		(fp_line
			(start -0.67945 -0.3048)
			(end -0.67945 0.3048)
			(stroke
				(width 0.1)
				(type default)
			)
			(layer "B.Fab")
		)
		(fp_line
			(start -0.67945 0.3048)
			(end -0.120396 0.3048)
			(stroke
				(width 0.1)
				(type default)
			)
			(layer "B.Fab")
		)
		(fp_line
			(start -0.12065 -0.3048)
			(end -0.67945 -0.3048)
			(stroke
				(width 0.1)
				(type default)
			)
			(layer "B.Fab")
		)
		(fp_line
			(start -0.12065 -0.2794)
			(end -0.12065 -0.3048)
			(stroke
				(width 0.1)
				(type default)
			)
			(layer "B.Fab")
		)
		(fp_line
			(start -0.120396 0.2794)
			(end 0.12065 0.2794)
			(stroke
				(width 0.1)
				(type default)
			)
			(layer "B.Fab")
		)
		(fp_line
			(start -0.120396 0.3048)
			(end -0.120396 0.2794)
			(stroke
				(width 0.1)
				(type default)
			)
			(layer "B.Fab")
		)
		(fp_line
			(start 0.12065 -0.305054)
			(end 0.12065 -0.2794)
			(stroke
				(width 0.1)
				(type default)
			)
			(layer "B.Fab")
		)
		(fp_line
			(start 0.12065 -0.2794)
			(end -0.12065 -0.2794)
			(stroke
				(width 0.1)
				(type default)
			)
			(layer "B.Fab")
		)
		(fp_line
			(start 0.12065 0.2794)
			(end 0.12065 0.3048)
			(stroke
				(width 0.1)
				(type default)
			)
			(layer "B.Fab")
		)
		(fp_line
			(start 0.12065 0.3048)
			(end 0.67945 0.3048)
			(stroke
				(width 0.1)
				(type default)
			)
			(layer "B.Fab")
		)
		(fp_line
			(start 0.67945 -0.305054)
			(end 0.12065 -0.305054)
			(stroke
				(width 0.1)
				(type default)
			)
			(layer "B.Fab")
		)
		(fp_line
			(start 0.67945 0.3048)
			(end 0.67945 -0.305054)
			(stroke
				(width 0.1)
				(type default)
			)
			(layer "B.Fab")
		)
		(pad "1" smd circle
			(at 0.40005 0 180)
			(size 0 0)
			(layers "B.Cu" "B.Mask" "B.Paste")
			(net "FM_AC_PWR_CYCLE_R_BUF")
		)
		(pad "2" smd circle
			(at -0.40005 0 180)
			(size 0 0)
			(layers "B.Cu" "B.Mask" "B.Paste")
			(net "GND")
		)
	)
	(footprint ""
		(layer "B.Cu")
		(at 103.886 -76.708 90)
		(property "Reference" "PR324"
			(at 0 0 90)
			(layer "B.SilkS")
			(hide yes)
			(effects
				(font
					(size 1.27 1.27)
				)
				(justify mirror)
			)
		)
		(property "Value" ""
			(at 0 0 90)
			(layer "B.Fab")
			(effects
				(font
					(size 1.27 1.27)
				)
				(justify mirror)
			)
		)
		(duplicate_pad_numbers_are_jumpers no)
		(fp_line
			(start 0.7874 -0.4064)
			(end -0.7874 -0.4064)
			(stroke
				(width 0.1524)
				(type default)
			)
			(layer "B.SilkS")
		)
		(fp_line
			(start -0.7874 -0.4064)
			(end -0.7874 0.4064)
			(stroke
				(width 0.1524)
				(type default)
			)
			(layer "B.SilkS")
		)
		(fp_line
			(start 0.7874 0.4064)
			(end 0.7874 -0.4064)
			(stroke
				(width 0.1524)
				(type default)
			)
			(layer "B.SilkS")
		)
		(fp_line
			(start -0.7874 0.4064)
			(end 0.7874 0.4064)
			(stroke
				(width 0.1524)
				(type default)
			)
			(layer "B.SilkS")
		)
		(fp_line
			(start 0.67945 -0.305054)
			(end 0.12065 -0.305054)
			(stroke
				(width 0.1)
				(type default)
			)
			(layer "B.Fab")
		)
		(fp_line
			(start 0.12065 -0.305054)
			(end 0.12065 -0.2794)
			(stroke
				(width 0.1)
				(type default)
			)
			(layer "B.Fab")
		)
		(fp_line
			(start -0.12065 -0.3048)
			(end -0.67945 -0.3048)
			(stroke
				(width 0.1)
				(type default)
			)
			(layer "B.Fab")
		)
		(fp_line
			(start -0.67945 -0.3048)
			(end -0.67945 0.3048)
			(stroke
				(width 0.1)
				(type default)
			)
			(layer "B.Fab")
		)
		(fp_line
			(start 0.12065 -0.2794)
			(end -0.12065 -0.2794)
			(stroke
				(width 0.1)
				(type default)
			)
			(layer "B.Fab")
		)
		(fp_line
			(start -0.12065 -0.2794)
			(end -0.12065 -0.3048)
			(stroke
				(width 0.1)
				(type default)
			)
			(layer "B.Fab")
		)
		(fp_line
			(start 0.12065 0.2794)
			(end 0.12065 0.3048)
			(stroke
				(width 0.1)
				(type default)
			)
			(layer "B.Fab")
		)
		(fp_line
			(start -0.120396 0.2794)
			(end 0.12065 0.2794)
			(stroke
				(width 0.1)
				(type default)
			)
			(layer "B.Fab")
		)
		(fp_line
			(start 0.67945 0.3048)
			(end 0.67945 -0.305054)
			(stroke
				(width 0.1)
				(type default)
			)
			(layer "B.Fab")
		)
		(fp_line
			(start 0.12065 0.3048)
			(end 0.67945 0.3048)
			(stroke
				(width 0.1)
				(type default)
			)
			(layer "B.Fab")
		)
		(fp_line
			(start -0.120396 0.3048)
			(end -0.120396 0.2794)
			(stroke
				(width 0.1)
				(type default)
			)
			(layer "B.Fab")
		)
		(fp_line
			(start -0.67945 0.3048)
			(end -0.120396 0.3048)
			(stroke
				(width 0.1)
				(type default)
			)
			(layer "B.Fab")
		)
		(pad "1" smd circle
			(at 0.40005 0 270)
			(size 0 0)
			(layers "B.Cu" "B.Mask" "B.Paste")
			(net "P12V_MB1_SENSE+")
		)
		(pad "2" smd circle
			(at -0.40005 0 270)
			(size 0 0)
			(layers "B.Cu" "B.Mask" "B.Paste")
			(net "P12V_MB0_SENSE+")
		)
	)
	(footprint ""
		(layer "B.Cu")
		(at 292.608 -39.116 180)
		(property "Reference" "C100"
			(at 0 0 0)
			(layer "B.SilkS")
			(hide yes)
			(effects
				(font
					(size 1.27 1.27)
				)
				(justify mirror)
			)
		)
		(property "Value" ""
			(at 0 0 0)
			(layer "B.Fab")
			(effects
				(font
					(size 1.27 1.27)
				)
				(justify mirror)
			)
		)
		(duplicate_pad_numbers_are_jumpers no)
		(fp_line
			(start 0.7874 0.4064)
			(end 0.7874 -0.4064)
			(stroke
				(width 0.1524)
				(type default)
			)
			(layer "B.SilkS")
		)
		(fp_line
			(start 0.7874 -0.4064)
			(end -0.7874 -0.4064)
			(stroke
				(width 0.1524)
				(type default)
			)
			(layer "B.SilkS")
		)
		(fp_line
			(start -0.7874 0.4064)
			(end 0.7874 0.4064)
			(stroke
				(width 0.1524)
				(type default)
			)
			(layer "B.SilkS")
		)
		(fp_line
			(start -0.7874 -0.4064)
			(end -0.7874 0.4064)
			(stroke
				(width 0.1524)
				(type default)
			)
			(layer "B.SilkS")
		)
		(fp_line
			(start 0.67945 0.3048)
			(end 0.67945 -0.305054)
			(stroke
				(width 0.1)
				(type default)
			)
			(layer "B.Fab")
		)
		(fp_line
			(start 0.67945 -0.305054)
			(end 0.12065 -0.305054)
			(stroke
				(width 0.1)
				(type default)
			)
			(layer "B.Fab")
		)
		(fp_line
			(start 0.12065 0.3048)
			(end 0.67945 0.3048)
			(stroke
				(width 0.1)
				(type default)
			)
			(layer "B.Fab")
		)
		(fp_line
			(start 0.12065 0.2794)
			(end 0.12065 0.3048)
			(stroke
				(width 0.1)
				(type default)
			)
			(layer "B.Fab")
		)
		(fp_line
			(start 0.12065 -0.2794)
			(end -0.12065 -0.2794)
			(stroke
				(width 0.1)
				(type default)
			)
			(layer "B.Fab")
		)
		(fp_line
			(start 0.12065 -0.305054)
			(end 0.12065 -0.2794)
			(stroke
				(width 0.1)
				(type default)
			)
			(layer "B.Fab")
		)
		(fp_line
			(start -0.120396 0.3048)
			(end -0.120396 0.2794)
			(stroke
				(width 0.1)
				(type default)
			)
			(layer "B.Fab")
		)
		(fp_line
			(start -0.120396 0.2794)
			(end 0.12065 0.2794)
			(stroke
				(width 0.1)
				(type default)
			)
			(layer "B.Fab")
		)
		(fp_line
			(start -0.12065 -0.2794)
			(end -0.12065 -0.3048)
			(stroke
				(width 0.1)
				(type default)
			)
			(layer "B.Fab")
		)
		(fp_line
			(start -0.12065 -0.3048)
			(end -0.67945 -0.3048)
			(stroke
				(width 0.1)
				(type default)
			)
			(layer "B.Fab")
		)
		(fp_line
			(start -0.67945 0.3048)
			(end -0.120396 0.3048)
			(stroke
				(width 0.1)
				(type default)
			)
			(layer "B.Fab")
		)
		(fp_line
			(start -0.67945 -0.3048)
			(end -0.67945 0.3048)
			(stroke
				(width 0.1)
				(type default)
			)
			(layer "B.Fab")
		)
		(pad "1" smd circle
			(at 0.40005 0)
			(size 0 0)
			(layers "B.Cu" "B.Mask" "B.Paste")
			(net "FM_AC_PWR_CYCLE_R1_N")
		)
		(pad "2" smd circle
			(at -0.40005 0)
			(size 0 0)
			(layers "B.Cu" "B.Mask" "B.Paste")
			(net "GND")
		)
	)
	(footprint ""
		(layer "B.Cu")
		(at 236.982 -95.504 90)
		(property "Reference" "C32"
			(at 0 0 90)
			(layer "B.SilkS")
			(hide yes)
			(effects
				(font
					(size 1.27 1.27)
				)
				(justify mirror)
			)
		)
		(property "Value" ""
			(at 0 0 90)
			(layer "B.Fab")
			(effects
				(font
					(size 1.27 1.27)
				)
				(justify mirror)
			)
		)
		(duplicate_pad_numbers_are_jumpers no)
		(fp_line
			(start 2.2098 -0.9398)
			(end -2.2098 -0.9398)
			(stroke
				(width 0.1524)
				(type default)
			)
			(layer "B.SilkS")
		)
		(fp_line
			(start -2.2098 -0.9398)
			(end -2.2098 0.9398)
			(stroke
				(width 0.1524)
				(type default)
			)
			(layer "B.SilkS")
		)
		(fp_line
			(start 2.2098 0.9398)
			(end 2.2098 -0.9398)
			(stroke
				(width 0.1524)
				(type default)
			)
			(layer "B.SilkS")
		)
		(fp_line
			(start -2.2098 0.9398)
			(end 2.2098 0.9398)
			(stroke
				(width 0.1524)
				(type default)
			)
			(layer "B.SilkS")
		)
		(fp_line
			(start 1.700022 -0.899922)
			(end -1.700022 -0.899922)
			(stroke
				(width 0.1)
				(type default)
			)
			(layer "B.Fab")
		)
		(fp_line
			(start -1.700022 -0.899922)
			(end -1.700022 0.899922)
			(stroke
				(width 0.1)
				(type default)
			)
			(layer "B.Fab")
		)
		(fp_line
			(start 1.700022 0.899922)
			(end 1.700022 -0.899922)
			(stroke
				(width 0.1)
				(type default)
			)
			(layer "B.Fab")
		)
		(fp_line
			(start -1.700022 0.899922)
			(end 1.700022 0.899922)
			(stroke
				(width 0.1)
				(type default)
			)
			(layer "B.Fab")
		)
		(pad "1" smd rect
			(at 1.4732 0 90)
			(size 1.1684 1.5748)
			(layers "B.Cu" "B.Mask" "B.Paste")
			(net "P52V_HS")
		)
		(pad "2" smd rect
			(at -1.4732 0 90)
			(size 1.1684 1.5748)
			(layers "B.Cu" "B.Mask" "B.Paste")
			(net "GND")
		)
	)
	(footprint ""
		(layer "B.Cu")
		(at 277.709122 -93.203522 90)
		(property "Reference" "PC563"
			(at 0 0 90)
			(layer "B.SilkS")
			(hide yes)
			(effects
				(font
					(size 1.27 1.27)
				)
				(justify mirror)
			)
		)
		(property "Value" ""
			(at 0 0 90)
			(layer "B.Fab")
			(effects
				(font
					(size 1.27 1.27)
				)
				(justify mirror)
			)
		)
		(duplicate_pad_numbers_are_jumpers no)
		(fp_line
			(start 1.2954 -0.5842)
			(end -1.2954 -0.5842)
			(stroke
				(width 0.1524)
				(type default)
			)
			(layer "B.SilkS")
		)
		(fp_line
			(start -1.2954 -0.5842)
			(end -1.2954 0.5842)
			(stroke
				(width 0.1524)
				(type default)
			)
			(layer "B.SilkS")
		)
		(fp_line
			(start 1.2954 0.5842)
			(end 1.2954 -0.5842)
			(stroke
				(width 0.1524)
				(type default)
			)
			(layer "B.SilkS")
		)
		(fp_line
			(start -1.2954 0.5842)
			(end 1.2954 0.5842)
			(stroke
				(width 0.1524)
				(type default)
			)
			(layer "B.SilkS")
		)
		(fp_line
			(start 0.8636 -0.4572)
			(end -0.8636 -0.4572)
			(stroke
				(width 0.1)
				(type default)
			)
			(layer "B.Fab")
		)
		(fp_line
			(start -0.8636 -0.4572)
			(end -0.8636 -0.4064)
			(stroke
				(width 0.1)
				(type default)
			)
			(layer "B.Fab")
		)
		(fp_line
			(start 1.1938 -0.4064)
			(end 0.8636 -0.4064)
			(stroke
				(width 0.1)
				(type default)
			)
			(layer "B.Fab")
		)
		(fp_line
			(start 0.8636 -0.4064)
			(end 0.8636 -0.4572)
			(stroke
				(width 0.1)
				(type default)
			)
			(layer "B.Fab")
		)
		(fp_line
			(start -0.8636 -0.4064)
			(end -1.1938 -0.4064)
			(stroke
				(width 0.1)
				(type default)
			)
			(layer "B.Fab")
		)
		(fp_line
			(start -1.1938 -0.4064)
			(end -1.1938 0.4064)
			(stroke
				(width 0.1)
				(type default)
			)
			(layer "B.Fab")
		)
		(fp_line
			(start 1.1938 0.4064)
			(end 1.1938 -0.4064)
			(stroke
				(width 0.1)
				(type default)
			)
			(layer "B.Fab")
		)
		(fp_line
			(start 0.8636 0.4064)
			(end 1.1938 0.4064)
			(stroke
				(width 0.1)
				(type default)
			)
			(layer "B.Fab")
		)
		(fp_line
			(start -0.8636 0.4064)
			(end -0.8636 0.4572)
			(stroke
				(width 0.1)
				(type default)
			)
			(layer "B.Fab")
		)
		(fp_line
			(start -1.1938 0.4064)
			(end -0.8636 0.4064)
			(stroke
				(width 0.1)
				(type default)
			)
			(layer "B.Fab")
		)
		(fp_line
			(start 0.8636 0.4572)
			(end 0.8636 0.4064)
			(stroke
				(width 0.1)
				(type default)
			)
			(layer "B.Fab")
		)
		(fp_line
			(start -0.8636 0.4572)
			(end 0.8636 0.4572)
			(stroke
				(width 0.1)
				(type default)
			)
			(layer "B.Fab")
		)
		(pad "1" smd rect
			(at 0.7366 0)
			(size 0.7112 0.8128)
			(layers "B.Cu" "B.Mask" "B.Paste")
			(net "GND")
		)
		(pad "2" smd rect
			(at -0.7366 0)
			(size 0.7112 0.8128)
			(layers "B.Cu" "B.Mask" "B.Paste")
			(net "P52V_HS1_GATE2_R1")
		)
	)
	(footprint ""
		(layer "B.Cu")
		(at 189.611 -82.423)
		(property "Reference" "R105"
			(at 0 0 0)
			(layer "B.SilkS")
			(hide yes)
			(effects
				(font
					(size 1.27 1.27)
				)
				(justify mirror)
			)
		)
		(property "Value" ""
			(at 0 0 0)
			(layer "B.Fab")
			(effects
				(font
					(size 1.27 1.27)
				)
				(justify mirror)
			)
		)
		(duplicate_pad_numbers_are_jumpers no)
		(fp_line
			(start -0.7874 -0.4064)
			(end -0.7874 0.4064)
			(stroke
				(width 0.1524)
				(type default)
			)
			(layer "B.SilkS")
		)
		(fp_line
			(start -0.7874 0.4064)
			(end 0.7874 0.4064)
			(stroke
				(width 0.1524)
				(type default)
			)
			(layer "B.SilkS")
		)
		(fp_line
			(start 0.7874 -0.4064)
			(end -0.7874 -0.4064)
			(stroke
				(width 0.1524)
				(type default)
			)
			(layer "B.SilkS")
		)
		(fp_line
			(start 0.7874 0.4064)
			(end 0.7874 -0.4064)
			(stroke
				(width 0.1524)
				(type default)
			)
			(layer "B.SilkS")
		)
		(fp_line
			(start -0.67945 -0.3048)
			(end -0.67945 0.3048)
			(stroke
				(width 0.1)
				(type default)
			)
			(layer "B.Fab")
		)
		(fp_line
			(start -0.67945 0.3048)
			(end -0.120396 0.3048)
			(stroke
				(width 0.1)
				(type default)
			)
			(layer "B.Fab")
		)
		(fp_line
			(start -0.12065 -0.3048)
			(end -0.67945 -0.3048)
			(stroke
				(width 0.1)
				(type default)
			)
			(layer "B.Fab")
		)
		(fp_line
			(start -0.12065 -0.2794)
			(end -0.12065 -0.3048)
			(stroke
				(width 0.1)
				(type default)
			)
			(layer "B.Fab")
		)
		(fp_line
			(start -0.120396 0.2794)
			(end 0.12065 0.2794)
			(stroke
				(width 0.1)
				(type default)
			)
			(layer "B.Fab")
		)
		(fp_line
			(start -0.120396 0.3048)
			(end -0.120396 0.2794)
			(stroke
				(width 0.1)
				(type default)
			)
			(layer "B.Fab")
		)
		(fp_line
			(start 0.12065 -0.305054)
			(end 0.12065 -0.2794)
			(stroke
				(width 0.1)
				(type default)
			)
			(layer "B.Fab")
		)
		(fp_line
			(start 0.12065 -0.2794)
			(end -0.12065 -0.2794)
			(stroke
				(width 0.1)
				(type default)
			)
			(layer "B.Fab")
		)
		(fp_line
			(start 0.12065 0.2794)
			(end 0.12065 0.3048)
			(stroke
				(width 0.1)
				(type default)
			)
			(layer "B.Fab")
		)
		(fp_line
			(start 0.12065 0.3048)
			(end 0.67945 0.3048)
			(stroke
				(width 0.1)
				(type default)
			)
			(layer "B.Fab")
		)
		(fp_line
			(start 0.67945 -0.305054)
			(end 0.12065 -0.305054)
			(stroke
				(width 0.1)
				(type default)
			)
			(layer "B.Fab")
		)
		(fp_line
			(start 0.67945 0.3048)
			(end 0.67945 -0.305054)
			(stroke
				(width 0.1)
				(type default)
			)
			(layer "B.Fab")
		)
		(pad "1" smd circle
			(at 0.40005 0 180)
			(size 0 0)
			(layers "B.Cu" "B.Mask" "B.Paste")
			(net "PU_9543_1_INT0")
		)
		(pad "2" smd circle
			(at -0.40005 0 180)
			(size 0 0)
			(layers "B.Cu" "B.Mask" "B.Paste")
			(net "P3V3_AUX")
		)
	)
)
